(kicad_pcb
	(version 20241229)
	(generator "pcbnew")
	(generator_version "9.0")
	(general
		(thickness 1.6296)
		(legacy_teardrops no)
	)
	(paper "A3")
	(title_block
		(title "Thunderbolt to 10GbE adapter")
		(date "2026-04-21")
		(rev "1.1.0")
		(company "Antmicro Ltd")
		(comment 1 "www.antmicro.com")
		(comment 9 "footprints 32-36 of 703")
	)
	(layers
		(0 "F.Cu" signal)
		(4 "In1.Cu" signal)
		(6 "In2.Cu" signal)
		(8 "In3.Cu" signal)
		(10 "In4.Cu" signal)
		(12 "In5.Cu" signal)
		(14 "In6.Cu" signal)
		(2 "B.Cu" signal)
		(9 "F.Adhes" user "F.Adhesive")
		(11 "B.Adhes" user "B.Adhesive")
		(13 "F.Paste" user)
		(15 "B.Paste" user)
		(5 "F.SilkS" user "F.Silkscreen")
		(7 "B.SilkS" user "B.Silkscreen")
		(1 "F.Mask" user)
		(3 "B.Mask" user)
		(17 "Dwgs.User" user "User.Drawings")
		(19 "Cmts.User" user "User.Comments")
		(21 "Eco1.User" user "User.Eco1")
		(23 "Eco2.User" user "User.Eco2")
		(25 "Edge.Cuts" user)
		(27 "Margin" user)
		(31 "F.CrtYd" user "F.Courtyard")
		(29 "B.CrtYd" user "B.Courtyard")
		(35 "F.Fab" user)
		(33 "B.Fab" user)
	)
	(footprint "antmicro-footprints:C_0603_1608Metric_EIA"
		(layer "F.Cu")
		(at 159.55 103.050001 -90)
		(descr "Capacitor SMD 0603, IPC-7351 Density Level A")
		(tags "Capacitor 0603")
		(property "Reference" "C147"
			(at 17.649996 -13.250002 270)
			(layer "F.SilkS")
			(effects
				(font
					(size 0.7 0.7)
					(thickness 0.15)
				)
			)
		)
		(property "Value" "C_22u_16V_0603"
			(at -1.42757 1.770288 270)
			(layer "F.Fab")
			(effects
				(font
					(size 0.7 0.7)
					(thickness 0.15)
				)
				(justify left bottom)
			)
		)
		(property "Datasheet" "https://product.samsungsem.com/mlcc/CL10A226MO7JZN.do"
			(at 0 0 270)
			(layer "F.Fab")
			(hide yes)
			(effects
				(font
					(size 1.27 1.27)
					(thickness 0.15)
				)
			)
		)
		(property "Description" "SMD Multilayer Ceramic Capacitor"
			(at 0 0 270)
			(layer "F.Fab")
			(hide yes)
			(effects
				(font
					(size 1.27 1.27)
					(thickness 0.15)
				)
			)
		)
		(property "MPN" "CL10A226MO7JZNC"
			(at 0 0 270)
			(unlocked yes)
			(layer "F.Fab")
			(hide yes)
			(effects
				(font
					(size 1 1)
					(thickness 0.15)
				)
			)
		)
		(property "Manufacturer" "Samsung Electro-Mechanics"
			(at 0 0 270)
			(unlocked yes)
			(layer "F.Fab")
			(hide yes)
			(effects
				(font
					(size 1 1)
					(thickness 0.15)
				)
			)
		)
		(property "License" "Apache-2.0"
			(at 0 0 270)
			(unlocked yes)
			(layer "F.Fab")
			(hide yes)
			(effects
				(font
					(size 1 1)
					(thickness 0.15)
				)
			)
		)
		(property "Author" "Antmicro"
			(at 0 0 270)
			(unlocked yes)
			(layer "F.Fab")
			(hide yes)
			(effects
				(font
					(size 1 1)
					(thickness 0.15)
				)
			)
		)
		(property "Val" "22u"
			(at 0 0 270)
			(unlocked yes)
			(layer "F.Fab")
			(hide yes)
			(effects
				(font
					(size 1 1)
					(thickness 0.15)
				)
			)
		)
		(property "Voltage" "16V"
			(at 0 0 270)
			(unlocked yes)
			(layer "F.Fab")
			(hide yes)
			(effects
				(font
					(size 1 1)
					(thickness 0.15)
				)
			)
		)
		(property "Dielectric" ""
			(at 0 0 270)
			(unlocked yes)
			(layer "F.Fab")
			(hide yes)
			(effects
				(font
					(size 1 1)
					(thickness 0.15)
				)
			)
		)
		(sheetname "/X710 DCDC converters/")
		(sheetfile "DCDC_converters_X710.kicad_sch")
		(attr smd)
		(fp_line
			(start -0.15 0.55)
			(end 0.15 0.55)
			(stroke
				(width 0.15)
				(type solid)
			)
			(layer "F.SilkS")
		)
		(fp_line
			(start -0.15 -0.55)
			(end 0.15 -0.55)
			(stroke
				(width 0.15)
				(type solid)
			)
			(layer "F.SilkS")
		)
		(fp_rect
			(start -1.25 -0.65)
			(end 1.25 0.65)
			(stroke
				(width 0.05)
				(type solid)
			)
			(fill no)
			(layer "F.CrtYd")
		)
		(fp_rect
			(start -0.8 -0.45)
			(end 0.8 0.45)
			(stroke
				(width 0.15)
				(type solid)
			)
			(fill no)
			(layer "F.Fab")
		)
		(fp_text user "Author: Antmicro"
			(at -1.682 4.894 270)
			(layer "F.Fab")
			(effects
				(font
					(size 0.7 0.7)
					(thickness 0.15)
				)
				(justify left bottom)
			)
		)
		(fp_text user "${REFERENCE}"
			(at -1.682 3.895 270)
			(layer "F.Fab")
			(effects
				(font
					(size 0.7 0.7)
					(thickness 0.15)
				)
				(justify left bottom)
			)
		)
		(fp_text user "License: Apache-2.0"
			(at -1.682 5.895 270)
			(layer "F.Fab")
			(effects
				(font
					(size 0.7 0.7)
					(thickness 0.15)
				)
				(justify left bottom)
			)
		)
		(pad "1" smd roundrect
			(at -0.7 0 270)
			(size 0.8 1.1)
			(layers "F.Cu" "F.Mask" "F.Paste")
			(roundrect_rratio 0.2)
			(net 23 "GND")
			(pintype "passive")
		)
		(pad "2" smd roundrect
			(at 0.7 0 270)
			(size 0.8 1.1)
			(layers "F.Cu" "F.Mask" "F.Paste")
			(roundrect_rratio 0.2)
			(net 339 "/X710 DCDC converters/+1V0_OUT")
			(pintype "passive")
		)
	)
	(footprint "antmicro-footprints:FB_0805_2012Metric"
		(layer "F.Cu")
		(at 166.665 63 -90)
		(descr "FERRITE BEAD 0805")
		(tags "FERRITE BEAD 0805")
		(property "Reference" "FB8"
			(at -1.1 -1.935 270)
			(layer "F.SilkS")
			(effects
				(font
					(size 0.7 0.7)
					(thickness 0.15)
				)
				(justify left bottom)
			)
		)
		(property "Value" "FB_330Z_1.5A_Murata-BLM21PG_0805"
			(at 0.001 1.801 270)
			(layer "F.Fab")
			(effects
				(font
					(size 0.7 0.7)
					(thickness 0.15)
				)
				(justify left bottom)
			)
		)
		(property "Datasheet" "https://www.murata.com/products/productdata/8796738977822/ENFA0005.pdf?1653276712000"
			(at 0 0 270)
			(layer "F.Fab")
			(hide yes)
			(effects
				(font
					(size 1.27 1.27)
					(thickness 0.15)
				)
			)
		)
		(property "Description" "Ferrite Bead, 0805 [2012 Metric], 330 ohm, 1.5 A, BLM21P, 0.07 ohm, ± 25%, DC power line"
			(at 0 0 270)
			(layer "F.Fab")
			(hide yes)
			(effects
				(font
					(size 1.27 1.27)
					(thickness 0.15)
				)
			)
		)
		(property "Val" "330Z/1.5A"
			(at 0 0 270)
			(unlocked yes)
			(layer "F.Fab")
			(hide yes)
			(effects
				(font
					(size 1 1)
					(thickness 0.15)
				)
			)
		)
		(property "MPN" "BLM21PG331SN1D"
			(at 0 0 270)
			(unlocked yes)
			(layer "F.Fab")
			(hide yes)
			(effects
				(font
					(size 1 1)
					(thickness 0.15)
				)
			)
		)
		(property "Manufacturer" "Murata"
			(at 0 0 270)
			(unlocked yes)
			(layer "F.Fab")
			(hide yes)
			(effects
				(font
					(size 1 1)
					(thickness 0.15)
				)
			)
		)
		(property "Current" ""
			(at 0 0 270)
			(unlocked yes)
			(layer "F.Fab")
			(hide yes)
			(effects
				(font
					(size 1 1)
					(thickness 0.15)
				)
			)
		)
		(property "Author" "Antmicro"
			(at 0 0 270)
			(unlocked yes)
			(layer "F.Fab")
			(hide yes)
			(effects
				(font
					(size 1 1)
					(thickness 0.15)
				)
			)
		)
		(property "License" "Apache-2.0"
			(at 0 0 270)
			(unlocked yes)
			(layer "F.Fab")
			(hide yes)
			(effects
				(font
					(size 1 1)
					(thickness 0.15)
				)
			)
		)
		(sheetname "/X710-AT2 10GbE/")
		(sheetfile "x710-at2-10gbe.kicad_sch")
		(attr smd)
		(fp_line
			(start -0.319 0.698)
			(end 0.281 0.698)
			(stroke
				(width 0.15)
				(type solid)
			)
			(layer "F.SilkS")
		)
		(fp_line
			(start -0.299 -0.698)
			(end 0.299 -0.698)
			(stroke
				(width 0.15)
				(type solid)
			)
			(layer "F.SilkS")
		)
		(fp_rect
			(start 1.95 -0.9)
			(end -1.95 0.9)
			(stroke
				(width 0.05)
				(type default)
			)
			(fill no)
			(layer "F.CrtYd")
		)
		(fp_line
			(start -0.948 0.681)
			(end 0.948 0.681)
			(stroke
				(width 0.15)
				(type solid)
			)
			(layer "F.Fab")
		)
		(fp_line
			(start -0.948 -0.676)
			(end -0.948 0.676)
			(stroke
				(width 0.15)
				(type solid)
			)
			(layer "F.Fab")
		)
		(fp_line
			(start 0.948 -0.676)
			(end 0.948 0.676)
			(stroke
				(width 0.15)
				(type solid)
			)
			(layer "F.Fab")
		)
		(fp_line
			(start -0.948 -0.681)
			(end 0.948 -0.681)
			(stroke
				(width 0.15)
				(type solid)
			)
			(layer "F.Fab")
		)
		(fp_text user "Author: Antmicro"
			(at -1.44 5.001 270)
			(layer "F.Fab")
			(effects
				(font
					(size 0.7 0.7)
					(thickness 0.15)
				)
				(justify left bottom)
			)
		)
		(fp_text user "${REFERENCE}"
			(at -1.44 3.801 270)
			(layer "F.Fab")
			(effects
				(font
					(size 0.7 0.7)
					(thickness 0.15)
				)
				(justify left bottom)
			)
		)
		(fp_text user "License: Apache-2.0"
			(at -1.44 6.201 270)
			(layer "F.Fab")
			(effects
				(font
					(size 0.7 0.7)
					(thickness 0.15)
				)
				(justify left bottom)
			)
		)
		(pad "1" smd roundrect
			(at -1.1 0 270)
			(size 1.2 1.3)
			(layers "F.Cu" "F.Mask" "F.Paste")
			(roundrect_rratio 0.25)
			(net 7 "+3V3")
			(pintype "passive")
		)
		(pad "2" smd roundrect
			(at 1.1 0 270)
			(size 1.2 1.3)
			(layers "F.Cu" "F.Mask" "F.Paste")
			(roundrect_rratio 0.25)
			(net 56 "/X710-AT2 10GbE/3V3_OSC")
			(pintype "passive")
		)
	)
	(footprint "antmicro-footprints:R_0402_1005Metric"
		(layer "F.Cu")
		(at 151.55 110.15 180)
		(descr "Resistor SMD 0402")
		(tags "resistor SMD 0402")
		(property "Reference" "R102"
			(at -14.149998 -17.25 180)
			(layer "F.SilkS")
			(effects
				(font
					(size 0.7 0.7)
					(thickness 0.15)
				)
			)
		)
		(property "Value" "R_63k4_0402"
			(at -1.011843 1.772047 180)
			(layer "F.Fab")
			(effects
				(font
					(size 0.7 0.7)
					(thickness 0.15)
				)
				(justify left bottom)
			)
		)
		(property "Datasheet" "https://industrial.panasonic.com/cdbs/www-data/pdf/RDM0000/AOA0000C307.pdf"
			(at 0 0 180)
			(layer "F.Fab")
			(hide yes)
			(effects
				(font
					(size 1.27 1.27)
					(thickness 0.15)
				)
			)
		)
		(property "Description" "SMD Chip Resistor, 63.4 kohm, ± 0.1%, 63 mW, 0402 [1005 Metric], Thin Film,  Precision"
			(at 0 0 180)
			(layer "F.Fab")
			(hide yes)
			(effects
				(font
					(size 1.27 1.27)
					(thickness 0.15)
				)
			)
		)
		(property "MPN" "ERA-2AEB6342X"
			(at 0 0 180)
			(unlocked yes)
			(layer "F.Fab")
			(hide yes)
			(effects
				(font
					(size 1 1)
					(thickness 0.15)
				)
			)
		)
		(property "Manufacturer" "Panasonic"
			(at 0 0 180)
			(unlocked yes)
			(layer "F.Fab")
			(hide yes)
			(effects
				(font
					(size 1 1)
					(thickness 0.15)
				)
			)
		)
		(property "License" "Apache-2.0"
			(at 0 0 180)
			(unlocked yes)
			(layer "F.Fab")
			(hide yes)
			(effects
				(font
					(size 1 1)
					(thickness 0.15)
				)
			)
		)
		(property "Author" "Antmicro"
			(at 0 0 180)
			(unlocked yes)
			(layer "F.Fab")
			(hide yes)
			(effects
				(font
					(size 1 1)
					(thickness 0.15)
				)
			)
		)
		(property "Val" "63k4"
			(at 0 0 180)
			(unlocked yes)
			(layer "F.Fab")
			(hide yes)
			(effects
				(font
					(size 1 1)
					(thickness 0.15)
				)
			)
		)
		(property "Tolerance" "0.1%"
			(at 0 0 180)
			(unlocked yes)
			(layer "F.Fab")
			(hide yes)
			(effects
				(font
					(size 1 1)
					(thickness 0.15)
				)
			)
		)
		(sheetname "/X710 DCDC converters/")
		(sheetfile "DCDC_converters_X710.kicad_sch")
		(attr smd)
		(fp_rect
			(start -0.925 -0.47)
			(end 0.925 0.47)
			(stroke
				(width 0.05)
				(type default)
			)
			(fill no)
			(layer "F.CrtYd")
		)
		(fp_rect
			(start -0.5 -0.25)
			(end 0.5 0.25)
			(stroke
				(width 0.15)
				(type solid)
			)
			(fill no)
			(layer "F.Fab")
		)
		(fp_text user "License: Apache-2.0"
			(at -0.95 5.169 180)
			(layer "F.Fab")
			(effects
				(font
					(size 0.7 0.7)
					(thickness 0.15)
				)
				(justify left bottom)
			)
		)
		(fp_text user "Author: Antmicro"
			(at -0.95 4.169 180)
			(layer "F.Fab")
			(effects
				(font
					(size 0.7 0.7)
					(thickness 0.15)
				)
				(justify left bottom)
			)
		)
		(fp_text user "${REFERENCE}"
			(at -0.95 3.168 180)
			(layer "F.Fab")
			(effects
				(font
					(size 0.7 0.7)
					(thickness 0.15)
				)
				(justify left bottom)
			)
		)
		(pad "1" smd roundrect
			(at -0.48 0 180)
			(size 0.59 0.64)
			(layers "F.Cu" "F.Mask" "F.Paste")
			(roundrect_rratio 0.25)
			(net 337 "/X710 DCDC converters/1V88_FB")
			(pintype "passive")
		)
		(pad "2" smd roundrect
			(at 0.48 0 180)
			(size 0.59 0.64)
			(layers "F.Cu" "F.Mask" "F.Paste")
			(roundrect_rratio 0.25)
			(net 338 "/X710 DCDC converters/+1V88_OUT")
			(pintype "passive")
		)
	)
	(footprint "antmicro-footprints:MP_Pad6mm_Drill3.2mm"
		(layer "F.Cu")
		(at 128 64 90)
		(property "Reference" "MP6"
			(at 2.8 -3.8 180)
			(layer "F.SilkS")
			(effects
				(font
					(size 0.7 0.7)
					(thickness 0.15)
				)
				(justify left bottom)
			)
		)
		(property "Value" "MP_Pad6mm_Drill3.2mm"
			(at 0 3.9 90)
			(layer "F.Fab")
			(effects
				(font
					(size 0.7 0.7)
					(thickness 0.15)
				)
				(justify left bottom)
			)
		)
		(property "Description" "Mechanical part"
			(at 0 0 90)
			(layer "F.Fab")
			(hide yes)
			(effects
				(font
					(size 1.27 1.27)
					(thickness 0.15)
				)
			)
		)
		(property "Author" "Antmicro"
			(at 0 0 90)
			(unlocked yes)
			(layer "F.Fab")
			(hide yes)
			(effects
				(font
					(size 1 1)
					(thickness 0.15)
				)
			)
		)
		(property "License" "Apache-2.0"
			(at 0 0 90)
			(unlocked yes)
			(layer "F.Fab")
			(hide yes)
			(effects
				(font
					(size 1 1)
					(thickness 0.15)
				)
			)
		)
		(sheetname "/")
		(sheetfile "thunderbolt-to-10gbe-adapter.kicad_sch")
		(attr exclude_from_pos_files exclude_from_bom)
		(fp_circle
			(center 0 0)
			(end 3.25 0)
			(stroke
				(width 0.05)
				(type default)
			)
			(fill no)
			(layer "F.CrtYd")
		)
		(fp_text user "License: Apache-2.0"
			(at -0.178 8.425 90)
			(layer "F.Fab")
			(effects
				(font
					(size 0.7 0.7)
					(thickness 0.15)
				)
				(justify left bottom)
			)
		)
		(fp_text user "${REFERENCE}"
			(at -0.178 6.025 90)
			(layer "F.Fab")
			(effects
				(font
					(size 0.7 0.7)
					(thickness 0.15)
				)
				(justify left bottom)
			)
		)
		(fp_text user "Author: Antmicro"
			(at -0.178 7.225 90)
			(layer "F.Fab")
			(effects
				(font
					(size 0.7 0.7)
					(thickness 0.15)
				)
				(justify left bottom)
			)
		)
		(pad "1" thru_hole circle
			(at 0 0 90)
			(size 6 6)
			(drill 3.2)
			(layers "*.Cu" "*.Mask")
			(remove_unused_layers no)
			(net 23 "GND")
			(pintype "passive")
		)
	)
	(footprint "antmicro-footprints:C_0603_1608Metric_EIA"
		(layer "F.Cu")
		(at 138.704999 99.775 -90)
		(descr "Capacitor SMD 0603, IPC-7351 Density Level A")
		(tags "Capacitor 0603")
		(property "Reference" "C261"
			(at -9.274999 -36.545001 270)
			(layer "F.SilkS")
			(effects
				(font
					(size 0.7 0.7)
					(thickness 0.15)
				)
			)
		)
		(property "Value" "C_22u_16V_0603"
			(at -1.42757 1.770288 270)
			(layer "F.Fab")
			(effects
				(font
					(size 0.7 0.7)
					(thickness 0.15)
				)
				(justify left bottom)
			)
		)
		(property "Datasheet" "https://product.samsungsem.com/mlcc/CL10A226MO7JZN.do"
			(at 0 0 270)
			(layer "F.Fab")
			(hide yes)
			(effects
				(font
					(size 1.27 1.27)
					(thickness 0.15)
				)
			)
		)
		(property "Description" "SMD Multilayer Ceramic Capacitor"
			(at 0 0 270)
			(layer "F.Fab")
			(hide yes)
			(effects
				(font
					(size 1.27 1.27)
					(thickness 0.15)
				)
			)
		)
		(property "MPN" "CL10A226MO7JZNC"
			(at 0 0 270)
			(unlocked yes)
			(layer "F.Fab")
			(hide yes)
			(effects
				(font
					(size 1 1)
					(thickness 0.15)
				)
			)
		)
		(property "Manufacturer" "Samsung Electro-Mechanics"
			(at 0 0 270)
			(unlocked yes)
			(layer "F.Fab")
			(hide yes)
			(effects
				(font
					(size 1 1)
					(thickness 0.15)
				)
			)
		)
		(property "License" "Apache-2.0"
			(at 0 0 270)
			(unlocked yes)
			(layer "F.Fab")
			(hide yes)
			(effects
				(font
					(size 1 1)
					(thickness 0.15)
				)
			)
		)
		(property "Author" "Antmicro"
			(at 0 0 270)
			(unlocked yes)
			(layer "F.Fab")
			(hide yes)
			(effects
				(font
					(size 1 1)
					(thickness 0.15)
				)
			)
		)
		(property "Val" "22u"
			(at 0 0 270)
			(unlocked yes)
			(layer "F.Fab")
			(hide yes)
			(effects
				(font
					(size 1 1)
					(thickness 0.15)
				)
			)
		)
		(property "Voltage" "16V"
			(at 0 0 270)
			(unlocked yes)
			(layer "F.Fab")
			(hide yes)
			(effects
				(font
					(size 1 1)
					(thickness 0.15)
				)
			)
		)
		(property "Dielectric" ""
			(at 0 0 270)
			(unlocked yes)
			(layer "F.Fab")
			(hide yes)
			(effects
				(font
					(size 1 1)
					(thickness 0.15)
				)
			)
		)
		(sheetname "/X710-AT2 power/")
		(sheetfile "x710-at2-power.kicad_sch")
		(attr smd)
		(fp_line
			(start -0.15 0.55)
			(end 0.15 0.55)
			(stroke
				(width 0.15)
				(type solid)
			)
			(layer "F.SilkS")
		)
		(fp_line
			(start -0.15 -0.55)
			(end 0.15 -0.55)
			(stroke
				(width 0.15)
				(type solid)
			)
			(layer "F.SilkS")
		)
		(fp_rect
			(start -1.25 -0.65)
			(end 1.25 0.65)
			(stroke
				(width 0.05)
				(type solid)
			)
			(fill no)
			(layer "F.CrtYd")
		)
		(fp_rect
			(start -0.8 -0.45)
			(end 0.8 0.45)
			(stroke
				(width 0.15)
				(type solid)
			)
			(fill no)
			(layer "F.Fab")
		)
		(fp_text user "Author: Antmicro"
			(at -1.682 4.894 270)
			(layer "F.Fab")
			(effects
				(font
					(size 0.7 0.7)
					(thickness 0.15)
				)
				(justify left bottom)
			)
		)
		(fp_text user "License: Apache-2.0"
			(at -1.682 5.895 270)
			(layer "F.Fab")
			(effects
				(font
					(size 0.7 0.7)
					(thickness 0.15)
				)
				(justify left bottom)
			)
		)
		(fp_text user "${REFERENCE}"
			(at -1.682 3.895 270)
			(layer "F.Fab")
			(effects
				(font
					(size 0.7 0.7)
					(thickness 0.15)
				)
				(justify left bottom)
			)
		)
		(pad "1" smd roundrect
			(at -0.7 0 270)
			(size 0.8 1.1)
			(layers "F.Cu" "F.Mask" "F.Paste")
			(roundrect_rratio 0.2)
			(net 23 "GND")
			(pintype "passive")
		)
		(pad "2" smd roundrect
			(at 0.7 0 270)
			(size 0.8 1.1)
			(layers "F.Cu" "F.Mask" "F.Paste")
			(roundrect_rratio 0.2)
			(net 9 "VCCD")
			(pintype "passive")
		)
	)
)
